# T6G (Grand Teton) — schematic netlist excerpt (pin names and nets, part order shuffled) for the footprints in the layout excerpt that follows; sources: Cadence DE-HDL packaged netlist, KiCad conversion of 04192023_DAF0TMB3IC0_F0TG_MB_C_brd_V02_OCP.brd

L13  Q_INDUCTOR  BLM21SN300SN1D/5A IND  pkg SMLF  page 290 : \1\ = P1V8_CPU0_RT_1D ; \2\ = P1V8_CPU0_RT1_1A
PR285  Q_RES  1K 1% CHIP  pkg 0402LF  page 193 : A = P3V3_AUX ; B = PVDDCR_SOC_P0_EN_GD
C1090  Q_CAP  0.1UF 25V 10% X7R  pkg 0402  page 258 : A = PVDD18_S5_P1_ADC_TIC ; B = GND

(kicad_pcb
	(version 20260206)
	(generator "pcbnew")
	(generator_version "10.0")
	(general
		(thickness 1.6)
		(legacy_teardrops no)
	)
	(paper "A4")
	(title_block
		(title "04192023_DAF0TMB3IC0_F0TG_MB_C_brd_V02_OCP.brd")
		(comment 1 "Grand Teton / footprints 5348-5350 of 8354")
	)
	(layers
		(0 "F.Cu" signal "TOP")
		(4 "In1.Cu" signal "GND")
		(6 "In2.Cu" signal "IN1")
		(8 "In3.Cu" signal "GND1")
		(10 "In4.Cu" signal "IN2")
		(12 "In5.Cu" signal "GND2")
		(14 "In6.Cu" signal "IN3")
		(16 "In7.Cu" signal "GND3")
		(18 "In8.Cu" signal "VCC")
		(20 "In9.Cu" signal "VCC1")
		(22 "In10.Cu" signal "GND4")
		(24 "In11.Cu" signal "IN4")
		(26 "In12.Cu" signal "GND5")
		(28 "In13.Cu" signal "IN5")
		(30 "In14.Cu" signal "GND6")
		(32 "In15.Cu" signal "IN6")
		(34 "In16.Cu" signal "GND7")
		(2 "B.Cu" signal "BOTTOM")
		(9 "F.Adhes" user "F.Adhesive")
		(11 "B.Adhes" user "B.Adhesive")
		(13 "F.Paste" user "Package Geometry/Pastemask Top")
		(15 "B.Paste" user "Package Geometry/Pastemask Bottom")
		(5 "F.SilkS" user "Ref Des/Silkscreen Top")
		(7 "B.SilkS" user "Ref Des/Silkscreen Bottom")
		(1 "F.Mask" user "Board Geometry/Soldermask Top")
		(3 "B.Mask" user "Board Geometry/Soldermask Bottom")
		(17 "Dwgs.User" user "User.Drawings")
		(19 "Cmts.User" user "User.Comments")
		(21 "Eco1.User" user "User.Eco1")
		(23 "Eco2.User" user "User.Eco2")
		(25 "Edge.Cuts" user "Board Geometry/Outline")
		(27 "Margin" user)
		(31 "F.CrtYd" user "Package Geometry/Place Bound Top")
		(29 "B.CrtYd" user "Package Geometry/Place Bound Bottom")
		(35 "F.Fab" user "Ref Des/Assembly Top")
		(33 "B.Fab" user "Ref Des/Assembly Bottom")
	)
	(footprint ""
		(layer "B.Cu")
		(at 358.779826 -392.957558)
		(property "Reference" "L13"
			(at 0 0 0)
			(layer "B.SilkS")
			(hide yes)
			(effects
				(font
					(size 1.27 1.27)
				)
				(justify mirror)
			)
		)
		(property "Value" ""
			(at 0 0 0)
			(layer "B.Fab")
			(effects
				(font
					(size 1.27 1.27)
				)
				(justify mirror)
			)
		)
		(duplicate_pad_numbers_are_jumpers no)
		(fp_line
			(start -1.63576 -0.8128)
			(end -1.63576 0.8128)
			(stroke
				(width 0.1524)
				(type default)
			)
			(layer "B.SilkS")
		)
		(fp_line
			(start -1.63576 0.8128)
			(end 1.63576 0.8128)
			(stroke
				(width 0.1524)
				(type default)
			)
			(layer "B.SilkS")
		)
		(fp_line
			(start 1.63576 -0.8128)
			(end -1.63576 -0.8128)
			(stroke
				(width 0.1524)
				(type default)
			)
			(layer "B.SilkS")
		)
		(fp_line
			(start 1.63576 -0.8128)
			(end 1.63576 0.8128)
			(stroke
				(width 0.1524)
				(type default)
			)
			(layer "B.SilkS")
		)
		(fp_line
			(start -1.560576 -0.738632)
			(end 1.56083 -0.738632)
			(stroke
				(width 0.1)
				(type default)
			)
			(layer "B.Fab")
		)
		(fp_line
			(start -1.560576 0.7366)
			(end -1.560576 -0.738632)
			(stroke
				(width 0.1)
				(type default)
			)
			(layer "B.Fab")
		)
		(fp_line
			(start -1.524 0.7366)
			(end -1.560576 0.7366)
			(stroke
				(width 0.1)
				(type default)
			)
			(layer "B.Fab")
		)
		(fp_line
			(start 1.524 0.7366)
			(end -1.524 0.7366)
			(stroke
				(width 0.1)
				(type default)
			)
			(layer "B.Fab")
		)
		(fp_line
			(start 1.56083 -0.738632)
			(end 1.56083 0.7366)
			(stroke
				(width 0.1)
				(type default)
			)
			(layer "B.Fab")
		)
		(fp_line
			(start 1.56083 0.7366)
			(end 1.524 0.7366)
			(stroke
				(width 0.1)
				(type default)
			)
			(layer "B.Fab")
		)
		(pad "1" smd rect
			(at 0.94996 0)
			(size 1.1176 1.3716)
			(layers "B.Cu" "B.Mask" "B.Paste")
			(net "P1V8_CPU0_RT_1D")
		)
		(pad "2" smd rect
			(at -0.94996 0)
			(size 1.1176 1.3716)
			(layers "B.Cu" "B.Mask" "B.Paste")
			(net "P1V8_CPU0_RT1_1A")
		)
	)
	(footprint ""
		(layer "B.Cu")
		(at 367.544858 -142.574772 180)
		(property "Reference" "PR285"
			(at 0 0 0)
			(layer "B.SilkS")
			(hide yes)
			(effects
				(font
					(size 1.27 1.27)
				)
				(justify mirror)
			)
		)
		(property "Value" ""
			(at 0 0 0)
			(layer "B.Fab")
			(effects
				(font
					(size 1.27 1.27)
				)
				(justify mirror)
			)
		)
		(duplicate_pad_numbers_are_jumpers no)
		(fp_line
			(start 0.7874 0.4064)
			(end 0.7874 -0.4064)
			(stroke
				(width 0.1524)
				(type default)
			)
			(layer "B.SilkS")
		)
		(fp_line
			(start 0.7874 -0.4064)
			(end -0.7874 -0.4064)
			(stroke
				(width 0.1524)
				(type default)
			)
			(layer "B.SilkS")
		)
		(fp_line
			(start -0.7874 0.4064)
			(end 0.7874 0.4064)
			(stroke
				(width 0.1524)
				(type default)
			)
			(layer "B.SilkS")
		)
		(fp_line
			(start -0.7874 -0.4064)
			(end -0.7874 0.4064)
			(stroke
				(width 0.1524)
				(type default)
			)
			(layer "B.SilkS")
		)
		(fp_line
			(start 0.67945 0.3048)
			(end 0.67945 -0.305054)
			(stroke
				(width 0.1)
				(type default)
			)
			(layer "B.Fab")
		)
		(fp_line
			(start 0.67945 -0.305054)
			(end 0.12065 -0.305054)
			(stroke
				(width 0.1)
				(type default)
			)
			(layer "B.Fab")
		)
		(fp_line
			(start 0.12065 0.3048)
			(end 0.67945 0.3048)
			(stroke
				(width 0.1)
				(type default)
			)
			(layer "B.Fab")
		)
		(fp_line
			(start 0.12065 0.2794)
			(end 0.12065 0.3048)
			(stroke
				(width 0.1)
				(type default)
			)
			(layer "B.Fab")
		)
		(fp_line
			(start 0.12065 -0.2794)
			(end -0.12065 -0.2794)
			(stroke
				(width 0.1)
				(type default)
			)
			(layer "B.Fab")
		)
		(fp_line
			(start 0.12065 -0.305054)
			(end 0.12065 -0.2794)
			(stroke
				(width 0.1)
				(type default)
			)
			(layer "B.Fab")
		)
		(fp_line
			(start -0.120396 0.3048)
			(end -0.120396 0.2794)
			(stroke
				(width 0.1)
				(type default)
			)
			(layer "B.Fab")
		)
		(fp_line
			(start -0.120396 0.2794)
			(end 0.12065 0.2794)
			(stroke
				(width 0.1)
				(type default)
			)
			(layer "B.Fab")
		)
		(fp_line
			(start -0.12065 -0.2794)
			(end -0.12065 -0.3048)
			(stroke
				(width 0.1)
				(type default)
			)
			(layer "B.Fab")
		)
		(fp_line
			(start -0.12065 -0.3048)
			(end -0.67945 -0.3048)
			(stroke
				(width 0.1)
				(type default)
			)
			(layer "B.Fab")
		)
		(fp_line
			(start -0.67945 0.3048)
			(end -0.120396 0.3048)
			(stroke
				(width 0.1)
				(type default)
			)
			(layer "B.Fab")
		)
		(fp_line
			(start -0.67945 -0.3048)
			(end -0.67945 0.3048)
			(stroke
				(width 0.1)
				(type default)
			)
			(layer "B.Fab")
		)
		(pad "1" smd circle
			(at 0.40005 0)
			(size 0 0)
			(layers "B.Cu" "B.Mask" "B.Paste")
			(net "P3V3_AUX")
		)
		(pad "2" smd circle
			(at -0.40005 0)
			(size 0 0)
			(layers "B.Cu" "B.Mask" "B.Paste")
			(net "PVDDCR_SOC_P0_EN_GD")
		)
	)
	(footprint ""
		(layer "B.Cu")
		(at 228.420422 -329.698858 180)
		(property "Reference" "C1090"
			(at 0 0 0)
			(layer "B.SilkS")
			(hide yes)
			(effects
				(font
					(size 1.27 1.27)
				)
				(justify mirror)
			)
		)
		(property "Value" ""
			(at 0 0 0)
			(layer "B.Fab")
			(effects
				(font
					(size 1.27 1.27)
				)
				(justify mirror)
			)
		)
		(duplicate_pad_numbers_are_jumpers no)
		(fp_line
			(start 0.7874 0.4064)
			(end 0.7874 -0.4064)
			(stroke
				(width 0.1524)
				(type default)
			)
			(layer "B.SilkS")
		)
		(fp_line
			(start 0.7874 -0.4064)
			(end -0.7874 -0.4064)
			(stroke
				(width 0.1524)
				(type default)
			)
			(layer "B.SilkS")
		)
		(fp_line
			(start -0.7874 0.4064)
			(end 0.7874 0.4064)
			(stroke
				(width 0.1524)
				(type default)
			)
			(layer "B.SilkS")
		)
		(fp_line
			(start -0.7874 -0.4064)
			(end -0.7874 0.4064)
			(stroke
				(width 0.1524)
				(type default)
			)
			(layer "B.SilkS")
		)
		(fp_line
			(start 0.67945 0.3048)
			(end 0.67945 -0.305054)
			(stroke
				(width 0.1)
				(type default)
			)
			(layer "B.Fab")
		)
		(fp_line
			(start 0.67945 -0.305054)
			(end 0.12065 -0.305054)
			(stroke
				(width 0.1)
				(type default)
			)
			(layer "B.Fab")
		)
		(fp_line
			(start 0.12065 0.3048)
			(end 0.67945 0.3048)
			(stroke
				(width 0.1)
				(type default)
			)
			(layer "B.Fab")
		)
		(fp_line
			(start 0.12065 0.2794)
			(end 0.12065 0.3048)
			(stroke
				(width 0.1)
				(type default)
			)
			(layer "B.Fab")
		)
		(fp_line
			(start 0.12065 -0.2794)
			(end -0.12065 -0.2794)
			(stroke
				(width 0.1)
				(type default)
			)
			(layer "B.Fab")
		)
		(fp_line
			(start 0.12065 -0.305054)
			(end 0.12065 -0.2794)
			(stroke
				(width 0.1)
				(type default)
			)
			(layer "B.Fab")
		)
		(fp_line
			(start -0.120396 0.3048)
			(end -0.120396 0.2794)
			(stroke
				(width 0.1)
				(type default)
			)
			(layer "B.Fab")
		)
		(fp_line
			(start -0.120396 0.2794)
			(end 0.12065 0.2794)
			(stroke
				(width 0.1)
				(type default)
			)
			(layer "B.Fab")
		)
		(fp_line
			(start -0.12065 -0.2794)
			(end -0.12065 -0.3048)
			(stroke
				(width 0.1)
				(type default)
			)
			(layer "B.Fab")
		)
		(fp_line
			(start -0.12065 -0.3048)
			(end -0.67945 -0.3048)
			(stroke
				(width 0.1)
				(type default)
			)
			(layer "B.Fab")
		)
		(fp_line
			(start -0.67945 0.3048)
			(end -0.120396 0.3048)
			(stroke
				(width 0.1)
				(type default)
			)
			(layer "B.Fab")
		)
		(fp_line
			(start -0.67945 -0.3048)
			(end -0.67945 0.3048)
			(stroke
				(width 0.1)
				(type default)
			)
			(layer "B.Fab")
		)
		(pad "1" smd circle
			(at 0.40005 0)
			(size 0 0)
			(layers "B.Cu" "B.Mask" "B.Paste")
			(net "PVDD18_S5_P1_ADC_TIC")
		)
		(pad "2" smd circle
			(at -0.40005 0)
			(size 0 0)
			(layers "B.Cu" "B.Mask" "B.Paste")
			(net "GND")
		)
	)
)
